(kicad_pcb
	(version 20241229)
	(generator "pcbnew")
	(generator_version "9.0")
	(general
		(thickness 0.876)
		(legacy_teardrops no)
	)
	(paper "A4")
	(title_block
		(rev "1.2.2")
		(comment 9 "footprints 6-10 of 20")
	)
	(layers
		(0 "F.Cu" signal)
		(4 "In1.Cu" signal)
		(6 "In2.Cu" signal)
		(2 "B.Cu" signal)
		(9 "F.Adhes" user "F.Adhesive")
		(11 "B.Adhes" user "B.Adhesive")
		(13 "F.Paste" user)
		(15 "B.Paste" user)
		(5 "F.SilkS" user "F.Silkscreen")
		(7 "B.SilkS" user "B.Silkscreen")
		(1 "F.Mask" user)
		(3 "B.Mask" user)
		(17 "Dwgs.User" user "User.Drawings")
		(19 "Cmts.User" user "User.Comments")
		(21 "Eco1.User" user "User.Eco1")
		(23 "Eco2.User" user "User.Eco2")
		(25 "Edge.Cuts" user)
		(27 "Margin" user)
		(31 "F.CrtYd" user "F.Courtyard")
		(29 "B.CrtYd" user "B.Courtyard")
		(35 "F.Fab" user)
		(33 "B.Fab" user)
	)
	(footprint "antmicro-footprints:C_0402_1005Metric"
		(layer "B.Cu")
		(at 145.725059 112.367277 180)
		(descr "Capacitor SMD 0402")
		(tags "capacitor SMD 0402")
		(property "Reference" "C1"
			(at -1.575 -0.03 0)
			(layer "B.SilkS")
			(effects
				(font
					(size 0.7 0.7)
					(thickness 0.15)
				)
				(justify mirror)
			)
		)
		(property "Value" "C_100n_16V_X7R_0402"
			(at 0 -1.17 0)
			(layer "B.Fab")
			(effects
				(font
					(size 1 1)
					(thickness 0.15)
				)
				(justify mirror)
			)
		)
		(property "Datasheet" "https://www.kemet.com/en/us/capacitors/product/C0402C104J4RAC7411.html"
			(at 0 0 180)
			(layer "F.Fab")
			(hide yes)
			(effects
				(font
					(size 1.27 1.27)
					(thickness 0.15)
				)
			)
		)
		(property "Description" "SMD Multilayer Ceramic Capacitor, 100nF, 50V, 0402, ±5%, X7R"
			(at 0 0 180)
			(layer "F.Fab")
			(hide yes)
			(effects
				(font
					(size 1.27 1.27)
					(thickness 0.15)
				)
			)
		)
		(property "Author" "Antmicro"
			(at 291.450118 224.734554 0)
			(layer "B.Fab")
			(hide yes)
			(effects
				(font
					(size 1 1)
					(thickness 0.15)
				)
				(justify mirror)
			)
		)
		(property "Dielectric" "X7R"
			(at 291.450118 224.734554 0)
			(layer "B.Fab")
			(hide yes)
			(effects
				(font
					(size 1 1)
					(thickness 0.15)
				)
				(justify mirror)
			)
		)
		(property "License" "Apache-2.0"
			(at 291.450118 224.734554 0)
			(layer "B.Fab")
			(hide yes)
			(effects
				(font
					(size 1 1)
					(thickness 0.15)
				)
				(justify mirror)
			)
		)
		(property "MPN" "C0402C104J4RAC7411"
			(at 291.450118 224.734554 0)
			(layer "B.Fab")
			(hide yes)
			(effects
				(font
					(size 1 1)
					(thickness 0.15)
				)
				(justify mirror)
			)
		)
		(property "Manufacturer" "KEMET"
			(at 291.450118 224.734554 0)
			(layer "B.Fab")
			(hide yes)
			(effects
				(font
					(size 1 1)
					(thickness 0.15)
				)
				(justify mirror)
			)
		)
		(property "Val" "100n"
			(at 291.450118 224.734554 0)
			(layer "B.Fab")
			(hide yes)
			(effects
				(font
					(size 1 1)
					(thickness 0.15)
				)
				(justify mirror)
			)
		)
		(property "Voltage" "16V"
			(at 291.450118 224.734554 0)
			(layer "B.Fab")
			(hide yes)
			(effects
				(font
					(size 1 1)
					(thickness 0.15)
				)
				(justify mirror)
			)
		)
		(sheetname "/")
		(sheetfile "m2-pcie-adapter.kicad_sch")
		(attr smd)
		(fp_rect
			(start -0.925 0.47)
			(end 0.925 -0.47)
			(stroke
				(width 0.05)
				(type default)
			)
			(fill no)
			(layer "B.CrtYd")
		)
		(fp_line
			(start 0.504 0.25)
			(end 0.504 -0.248)
			(stroke
				(width 0.15)
				(type solid)
			)
			(layer "B.Fab")
		)
		(fp_line
			(start 0.504 -0.248)
			(end -0.494 -0.248)
			(stroke
				(width 0.15)
				(type solid)
			)
			(layer "B.Fab")
		)
		(fp_line
			(start -0.494 0.25)
			(end 0.504 0.25)
			(stroke
				(width 0.15)
				(type solid)
			)
			(layer "B.Fab")
		)
		(fp_line
			(start -0.494 -0.248)
			(end -0.494 0.25)
			(stroke
				(width 0.15)
				(type solid)
			)
			(layer "B.Fab")
		)
		(fp_text user "${REFERENCE}"
			(at 0 0 0)
			(layer "B.Fab")
			(effects
				(font
					(size 0.25 0.25)
					(thickness 0.04)
				)
				(justify mirror)
			)
		)
		(pad "1" smd roundrect
			(at -0.48 0 180)
			(size 0.59 0.64)
			(layers "B.Cu" "B.Mask" "B.Paste")
			(roundrect_rratio 0.25)
			(net 30 "+12V")
			(pintype "passive")
		)
		(pad "2" smd roundrect
			(at 0.48 0 180)
			(size 0.59 0.64)
			(layers "B.Cu" "B.Mask" "B.Paste")
			(roundrect_rratio 0.25)
			(net 60 "GND")
			(pintype "passive")
		)
	)
	(footprint "antmicro-footprints:C_0402_1005Metric"
		(layer "B.Cu")
		(at 142.300059 111.197277)
		(descr "Capacitor SMD 0402")
		(tags "capacitor SMD 0402")
		(property "Reference" "C4"
			(at 0.1 -2.65 0)
			(layer "B.SilkS")
			(effects
				(font
					(size 0.7 0.7)
					(thickness 0.15)
				)
				(justify mirror)
			)
		)
		(property "Value" "C_100n_16V_X7R_0402"
			(at 0 -1.17 0)
			(layer "B.Fab")
			(effects
				(font
					(size 1 1)
					(thickness 0.15)
				)
				(justify mirror)
			)
		)
		(property "Datasheet" "https://www.kemet.com/en/us/capacitors/product/C0402C104J4RAC7411.html"
			(at 0 0 0)
			(layer "F.Fab")
			(hide yes)
			(effects
				(font
					(size 1.27 1.27)
					(thickness 0.15)
				)
			)
		)
		(property "Description" "SMD Multilayer Ceramic Capacitor, 100nF, 50V, 0402, ±5%, X7R"
			(at 0 0 0)
			(layer "F.Fab")
			(hide yes)
			(effects
				(font
					(size 1.27 1.27)
					(thickness 0.15)
				)
			)
		)
		(property "Author" "Antmicro"
			(at 0 0 0)
			(layer "B.Fab")
			(hide yes)
			(effects
				(font
					(size 1 1)
					(thickness 0.15)
				)
				(justify mirror)
			)
		)
		(property "Dielectric" "X7R"
			(at 0 0 0)
			(layer "B.Fab")
			(hide yes)
			(effects
				(font
					(size 1 1)
					(thickness 0.15)
				)
				(justify mirror)
			)
		)
		(property "License" "Apache-2.0"
			(at 0 0 0)
			(layer "B.Fab")
			(hide yes)
			(effects
				(font
					(size 1 1)
					(thickness 0.15)
				)
				(justify mirror)
			)
		)
		(property "MPN" "C0402C104J4RAC7411"
			(at 0 0 0)
			(layer "B.Fab")
			(hide yes)
			(effects
				(font
					(size 1 1)
					(thickness 0.15)
				)
				(justify mirror)
			)
		)
		(property "Manufacturer" "KEMET"
			(at 0 0 0)
			(layer "B.Fab")
			(hide yes)
			(effects
				(font
					(size 1 1)
					(thickness 0.15)
				)
				(justify mirror)
			)
		)
		(property "Val" "100n"
			(at 0 0 0)
			(layer "B.Fab")
			(hide yes)
			(effects
				(font
					(size 1 1)
					(thickness 0.15)
				)
				(justify mirror)
			)
		)
		(property "Voltage" "16V"
			(at 0 0 0)
			(layer "B.Fab")
			(hide yes)
			(effects
				(font
					(size 1 1)
					(thickness 0.15)
				)
				(justify mirror)
			)
		)
		(sheetname "/")
		(sheetfile "m2-pcie-adapter.kicad_sch")
		(attr smd)
		(fp_rect
			(start -0.925 0.47)
			(end 0.925 -0.47)
			(stroke
				(width 0.05)
				(type default)
			)
			(fill no)
			(layer "B.CrtYd")
		)
		(fp_line
			(start -0.494 -0.248)
			(end -0.494 0.25)
			(stroke
				(width 0.15)
				(type solid)
			)
			(layer "B.Fab")
		)
		(fp_line
			(start -0.494 0.25)
			(end 0.504 0.25)
			(stroke
				(width 0.15)
				(type solid)
			)
			(layer "B.Fab")
		)
		(fp_line
			(start 0.504 -0.248)
			(end -0.494 -0.248)
			(stroke
				(width 0.15)
				(type solid)
			)
			(layer "B.Fab")
		)
		(fp_line
			(start 0.504 0.25)
			(end 0.504 -0.248)
			(stroke
				(width 0.15)
				(type solid)
			)
			(layer "B.Fab")
		)
		(fp_text user "${REFERENCE}"
			(at 0 0 0)
			(layer "B.Fab")
			(effects
				(font
					(size 0.25 0.25)
					(thickness 0.04)
				)
				(justify mirror)
			)
		)
		(pad "1" smd roundrect
			(at -0.48 0)
			(size 0.59 0.64)
			(layers "B.Cu" "B.Mask" "B.Paste")
			(roundrect_rratio 0.25)
			(net 31 "/+3V3")
			(pintype "passive")
		)
		(pad "2" smd roundrect
			(at 0.48 0)
			(size 0.59 0.64)
			(layers "B.Cu" "B.Mask" "B.Paste")
			(roundrect_rratio 0.25)
			(net 60 "GND")
			(pintype "passive")
		)
	)
	(footprint "antmicro-footprints:R_0402_1005Metric"
		(layer "B.Cu")
		(at 138.000059 106.947277 -90)
		(descr "Resistor SMD 0402")
		(tags "resistor SMD 0402")
		(property "Reference" "R1"
			(at 0 1 90)
			(layer "B.SilkS")
			(effects
				(font
					(size 0.7 0.7)
					(thickness 0.15)
				)
				(justify mirror)
			)
		)
		(property "Value" "R_0R_0402"
			(at 0 -1.17 90)
			(layer "B.Fab")
			(effects
				(font
					(size 1 1)
					(thickness 0.15)
				)
				(justify mirror)
			)
		)
		(property "Datasheet" "https://industrial.panasonic.com/cdbs/www-data/pdf/RDA0000/AOA0000C301.pdf"
			(at 0 0 270)
			(layer "F.Fab")
			(hide yes)
			(effects
				(font
					(size 1.27 1.27)
					(thickness 0.15)
				)
			)
		)
		(property "Description" "SMD Chip Resistor, Jumper, 0 ohm, 100 mW, 0402 [1005 Metric], Thick Film, General Purpose"
			(at 0 0 270)
			(layer "F.Fab")
			(hide yes)
			(effects
				(font
					(size 1.27 1.27)
					(thickness 0.15)
				)
			)
		)
		(property "Author" "Antmicro"
			(at 31.052782 244.947336 0)
			(layer "B.Fab")
			(hide yes)
			(effects
				(font
					(size 1 1)
					(thickness 0.15)
				)
				(justify mirror)
			)
		)
		(property "Current" "1A"
			(at 31.052782 244.947336 0)
			(layer "B.Fab")
			(hide yes)
			(effects
				(font
					(size 1 1)
					(thickness 0.15)
				)
				(justify mirror)
			)
		)
		(property "License" "Apache-2.0"
			(at 31.052782 244.947336 0)
			(layer "B.Fab")
			(hide yes)
			(effects
				(font
					(size 1 1)
					(thickness 0.15)
				)
				(justify mirror)
			)
		)
		(property "MPN" "ERJ2GE0R00X"
			(at 31.052782 244.947336 0)
			(layer "B.Fab")
			(hide yes)
			(effects
				(font
					(size 1 1)
					(thickness 0.15)
				)
				(justify mirror)
			)
		)
		(property "Manufacturer" "Panasonic"
			(at 31.052782 244.947336 0)
			(layer "B.Fab")
			(hide yes)
			(effects
				(font
					(size 1 1)
					(thickness 0.15)
				)
				(justify mirror)
			)
		)
		(property "Public" "False"
			(at 31.052782 244.947336 0)
			(layer "B.Fab")
			(hide yes)
			(effects
				(font
					(size 1 1)
					(thickness 0.15)
				)
				(justify mirror)
			)
		)
		(property "Tolerance" ""
			(at 31.052782 244.947336 0)
			(layer "B.Fab")
			(hide yes)
			(effects
				(font
					(size 1 1)
					(thickness 0.15)
				)
				(justify mirror)
			)
		)
		(property "Val" "0R"
			(at 31.052782 244.947336 0)
			(layer "B.Fab")
			(hide yes)
			(effects
				(font
					(size 1 1)
					(thickness 0.15)
				)
				(justify mirror)
			)
		)
		(sheetname "/")
		(sheetfile "m2-pcie-adapter.kicad_sch")
		(attr smd)
		(fp_rect
			(start -0.925 0.47)
			(end 0.925 -0.47)
			(stroke
				(width 0.05)
				(type default)
			)
			(fill no)
			(layer "B.CrtYd")
		)
		(fp_rect
			(start -0.5 0.25)
			(end 0.5 -0.25)
			(stroke
				(width 0.15)
				(type solid)
			)
			(fill no)
			(layer "B.Fab")
		)
		(pad "1" smd roundrect
			(at -0.48 0 270)
			(size 0.59 0.64)
			(layers "B.Cu" "B.Mask" "B.Paste")
			(roundrect_rratio 0.25)
			(net 31 "/+3V3")
			(pintype "passive")
		)
		(pad "2" smd roundrect
			(at 0.48 0 270)
			(size 0.59 0.64)
			(layers "B.Cu" "B.Mask" "B.Paste")
			(roundrect_rratio 0.25)
			(net 62 "/+3V3_AUX")
			(pintype "passive")
		)
	)
	(footprint "antmicro-footprints:C_0603_1608Metric"
		(layer "B.Cu")
		(at 113.890059 88.567277)
		(descr "Capacitor SMD 0603")
		(tags "capacitor 0603")
		(property "Reference" "C7"
			(at 0.01 1.29 0)
			(layer "B.SilkS")
			(effects
				(font
					(size 0.7 0.7)
					(thickness 0.15)
				)
				(justify mirror)
			)
		)
		(property "Value" "C_1u_0603"
			(at 0 -1.9 0)
			(layer "B.Fab")
			(effects
				(font
					(size 1 1)
					(thickness 0.15)
				)
				(justify mirror)
			)
		)
		(property "Datasheet" "https://spicat.kyocera-avx.com/product/mlcc/chartview/0603YD105KAT2A/"
			(at 0 0 0)
			(layer "F.Fab")
			(hide yes)
			(effects
				(font
					(size 1.27 1.27)
					(thickness 0.15)
				)
			)
		)
		(property "Description" "SMD Multilayer Ceramic Capacitor, 1 µF, 16 V, 0603 [1608 Metric], ± 10%, X5R, AVX 0603 MLCC"
			(at 0 0 0)
			(layer "F.Fab")
			(hide yes)
			(effects
				(font
					(size 1.27 1.27)
					(thickness 0.15)
				)
			)
		)
		(property "Author" "Antmicro"
			(at 0 0 0)
			(layer "B.Fab")
			(hide yes)
			(effects
				(font
					(size 1 1)
					(thickness 0.15)
				)
				(justify mirror)
			)
		)
		(property "Dielectric" ""
			(at 0 0 0)
			(layer "B.Fab")
			(hide yes)
			(effects
				(font
					(size 1 1)
					(thickness 0.15)
				)
				(justify mirror)
			)
		)
		(property "License" "Apache-2.0"
			(at 0 0 0)
			(layer "B.Fab")
			(hide yes)
			(effects
				(font
					(size 1 1)
					(thickness 0.15)
				)
				(justify mirror)
			)
		)
		(property "MPN" "0603YD105KAT2A"
			(at 0 0 0)
			(layer "B.Fab")
			(hide yes)
			(effects
				(font
					(size 1 1)
					(thickness 0.15)
				)
				(justify mirror)
			)
		)
		(property "Manufacturer" "KYOCERA AVX"
			(at 0 0 0)
			(layer "B.Fab")
			(hide yes)
			(effects
				(font
					(size 1 1)
					(thickness 0.15)
				)
				(justify mirror)
			)
		)
		(property "Public" "False"
			(at 0 0 0)
			(layer "B.Fab")
			(hide yes)
			(effects
				(font
					(size 1 1)
					(thickness 0.15)
				)
				(justify mirror)
			)
		)
		(property "Val" "1u"
			(at 0 0 0)
			(layer "B.Fab")
			(hide yes)
			(effects
				(font
					(size 1 1)
					(thickness 0.15)
				)
				(justify mirror)
			)
		)
		(property "Voltage" ""
			(at 0 0 0)
			(layer "B.Fab")
			(hide yes)
			(effects
				(font
					(size 1 1)
					(thickness 0.15)
				)
				(justify mirror)
			)
		)
		(sheetname "/")
		(sheetfile "m2-pcie-adapter.kicad_sch")
		(attr smd)
		(fp_line
			(start -0.15 -0.4)
			(end 0.15 -0.4)
			(stroke
				(width 0.15)
				(type solid)
			)
			(layer "B.SilkS")
		)
		(fp_line
			(start -0.15 0.4)
			(end 0.15 0.4)
			(stroke
				(width 0.15)
				(type solid)
			)
			(layer "B.SilkS")
		)
		(fp_rect
			(start -1.25 0.65)
			(end 1.25 -0.65)
			(stroke
				(width 0.05)
				(type solid)
			)
			(fill no)
			(layer "B.CrtYd")
		)
		(fp_rect
			(start -0.8 0.4)
			(end 0.8 -0.4)
			(stroke
				(width 0.15)
				(type solid)
			)
			(fill no)
			(layer "B.Fab")
		)
		(pad "1" smd roundrect
			(at -0.7 0)
			(size 0.8 1)
			(layers "B.Cu" "B.Mask" "B.Paste")
			(roundrect_rratio 0.2)
			(net 31 "/+3V3")
			(pintype "passive")
		)
		(pad "2" smd roundrect
			(at 0.7 0)
			(size 0.8 1)
			(layers "B.Cu" "B.Mask" "B.Paste")
			(roundrect_rratio 0.2)
			(net 60 "GND")
			(pintype "passive")
		)
	)
	(footprint "antmicro-footprints:C_0603_1608Metric"
		(layer "B.Cu")
		(at 145.510059 114.017277 180)
		(descr "Capacitor SMD 0603")
		(tags "capacitor 0603")
		(property "Reference" "C2"
			(at -1.89 -0.01 0)
			(layer "B.SilkS")
			(effects
				(font
					(size 0.7 0.7)
					(thickness 0.15)
				)
				(justify mirror)
			)
		)
		(property "Value" "C_1u_0603"
			(at 0 -1.9 0)
			(layer "B.Fab")
			(effects
				(font
					(size 1 1)
					(thickness 0.15)
				)
				(justify mirror)
			)
		)
		(property "Datasheet" "https://spicat.kyocera-avx.com/product/mlcc/chartview/0603YD105KAT2A/"
			(at 0 0 180)
			(layer "F.Fab")
			(hide yes)
			(effects
				(font
					(size 1.27 1.27)
					(thickness 0.15)
				)
			)
		)
		(property "Description" "SMD Multilayer Ceramic Capacitor, 1 µF, 16 V, 0603 [1608 Metric], ± 10%, X5R, AVX 0603 MLCC"
			(at 0 0 180)
			(layer "F.Fab")
			(hide yes)
			(effects
				(font
					(size 1.27 1.27)
					(thickness 0.15)
				)
			)
		)
		(property "Author" "Antmicro"
			(at 291.020118 228.034554 0)
			(layer "B.Fab")
			(hide yes)
			(effects
				(font
					(size 1 1)
					(thickness 0.15)
				)
				(justify mirror)
			)
		)
		(property "Dielectric" ""
			(at 291.020118 228.034554 0)
			(layer "B.Fab")
			(hide yes)
			(effects
				(font
					(size 1 1)
					(thickness 0.15)
				)
				(justify mirror)
			)
		)
		(property "License" "Apache-2.0"
			(at 291.020118 228.034554 0)
			(layer "B.Fab")
			(hide yes)
			(effects
				(font
					(size 1 1)
					(thickness 0.15)
				)
				(justify mirror)
			)
		)
		(property "MPN" "0603YD105KAT2A"
			(at 291.020118 228.034554 0)
			(layer "B.Fab")
			(hide yes)
			(effects
				(font
					(size 1 1)
					(thickness 0.15)
				)
				(justify mirror)
			)
		)
		(property "Manufacturer" "KYOCERA AVX"
			(at 291.020118 228.034554 0)
			(layer "B.Fab")
			(hide yes)
			(effects
				(font
					(size 1 1)
					(thickness 0.15)
				)
				(justify mirror)
			)
		)
		(property "Public" "False"
			(at 291.020118 228.034554 0)
			(layer "B.Fab")
			(hide yes)
			(effects
				(font
					(size 1 1)
					(thickness 0.15)
				)
				(justify mirror)
			)
		)
		(property "Val" "1u"
			(at 291.020118 228.034554 0)
			(layer "B.Fab")
			(hide yes)
			(effects
				(font
					(size 1 1)
					(thickness 0.15)
				)
				(justify mirror)
			)
		)
		(property "Voltage" ""
			(at 291.020118 228.034554 0)
			(layer "B.Fab")
			(hide yes)
			(effects
				(font
					(size 1 1)
					(thickness 0.15)
				)
				(justify mirror)
			)
		)
		(sheetname "/")
		(sheetfile "m2-pcie-adapter.kicad_sch")
		(attr smd)
		(fp_line
			(start -0.15 0.4)
			(end 0.15 0.4)
			(stroke
				(width 0.15)
				(type solid)
			)
			(layer "B.SilkS")
		)
		(fp_line
			(start -0.15 -0.4)
			(end 0.15 -0.4)
			(stroke
				(width 0.15)
				(type solid)
			)
			(layer "B.SilkS")
		)
		(fp_rect
			(start -1.25 0.65)
			(end 1.25 -0.65)
			(stroke
				(width 0.05)
				(type solid)
			)
			(fill no)
			(layer "B.CrtYd")
		)
		(fp_rect
			(start -0.8 0.4)
			(end 0.8 -0.4)
			(stroke
				(width 0.15)
				(type solid)
			)
			(fill no)
			(layer "B.Fab")
		)
		(pad "1" smd roundrect
			(at -0.7 0 180)
			(size 0.8 1)
			(layers "B.Cu" "B.Mask" "B.Paste")
			(roundrect_rratio 0.2)
			(net 30 "+12V")
			(pintype "passive")
		)
		(pad "2" smd roundrect
			(at 0.7 0 180)
			(size 0.8 1)
			(layers "B.Cu" "B.Mask" "B.Paste")
			(roundrect_rratio 0.2)
			(net 60 "GND")
			(pintype "passive")
		)
	)
)
